(kicad_pcb
	(version 20260206)
	(generator "pcbnew")
	(generator_version "10.0")
	(general
		(thickness 1.6)
		(legacy_teardrops no)
	)
	(paper "A4")
	(title_block
		(title "04192023_DAF0TMB3IC0_F0TG_MB_C_brd_V02_OCP.brd")
		(comment 1 "Grand Teton / footprints 3183-3186 of 8354")
	)
	(layers
		(0 "F.Cu" signal "TOP")
		(4 "In1.Cu" signal "GND")
		(6 "In2.Cu" signal "IN1")
		(8 "In3.Cu" signal "GND1")
		(10 "In4.Cu" signal "IN2")
		(12 "In5.Cu" signal "GND2")
		(14 "In6.Cu" signal "IN3")
		(16 "In7.Cu" signal "GND3")
		(18 "In8.Cu" signal "VCC")
		(20 "In9.Cu" signal "VCC1")
		(22 "In10.Cu" signal "GND4")
		(24 "In11.Cu" signal "IN4")
		(26 "In12.Cu" signal "GND5")
		(28 "In13.Cu" signal "IN5")
		(30 "In14.Cu" signal "GND6")
		(32 "In15.Cu" signal "IN6")
		(34 "In16.Cu" signal "GND7")
		(2 "B.Cu" signal "BOTTOM")
		(9 "F.Adhes" user "F.Adhesive")
		(11 "B.Adhes" user "B.Adhesive")
		(13 "F.Paste" user "Package Geometry/Pastemask Top")
		(15 "B.Paste" user "Package Geometry/Pastemask Bottom")
		(5 "F.SilkS" user "Ref Des/Silkscreen Top")
		(7 "B.SilkS" user "Ref Des/Silkscreen Bottom")
		(1 "F.Mask" user "Board Geometry/Soldermask Top")
		(3 "B.Mask" user "Board Geometry/Soldermask Bottom")
		(17 "Dwgs.User" user "User.Drawings")
		(19 "Cmts.User" user "User.Comments")
		(21 "Eco1.User" user "User.Eco1")
		(23 "Eco2.User" user "User.Eco2")
		(25 "Edge.Cuts" user "Board Geometry/Outline")
		(27 "Margin" user)
		(31 "F.CrtYd" user "Package Geometry/Place Bound Top")
		(29 "B.CrtYd" user "Package Geometry/Place Bound Bottom")
		(35 "F.Fab" user "Ref Des/Assembly Top")
		(33 "B.Fab" user "Ref Des/Assembly Bottom")
	)
	(footprint ""
		(layer "F.Cu")
		(at 95.489522 -136.066784 -90)
		(property "Reference" "C242"
			(at 0 0 270)
			(layer "F.SilkS")
			(hide yes)
			(effects
				(font
					(size 1.27 1.27)
				)
			)
		)
		(property "Value" ""
			(at 0 0 270)
			(layer "F.Fab")
			(effects
				(font
					(size 1.27 1.27)
				)
			)
		)
		(duplicate_pad_numbers_are_jumpers no)
		(fp_line
			(start -0.7874 0.4064)
			(end -0.7874 -0.4064)
			(stroke
				(width 0.1524)
				(type default)
			)
			(layer "F.SilkS")
		)
		(fp_line
			(start 0.7874 0.4064)
			(end -0.7874 0.4064)
			(stroke
				(width 0.1524)
				(type default)
			)
			(layer "F.SilkS")
		)
		(fp_line
			(start -0.7874 -0.4064)
			(end 0.7874 -0.4064)
			(stroke
				(width 0.1524)
				(type default)
			)
			(layer "F.SilkS")
		)
		(fp_line
			(start 0.7874 -0.4064)
			(end 0.7874 0.4064)
			(stroke
				(width 0.1524)
				(type default)
			)
			(layer "F.SilkS")
		)
		(fp_line
			(start -0.67945 0.3048)
			(end -0.67945 -0.305054)
			(stroke
				(width 0.1)
				(type default)
			)
			(layer "F.Fab")
		)
		(fp_line
			(start -0.12065 0.3048)
			(end -0.67945 0.3048)
			(stroke
				(width 0.1)
				(type default)
			)
			(layer "F.Fab")
		)
		(fp_line
			(start 0.120396 0.3048)
			(end 0.120396 0.2794)
			(stroke
				(width 0.1)
				(type default)
			)
			(layer "F.Fab")
		)
		(fp_line
			(start 0.67945 0.3048)
			(end 0.120396 0.3048)
			(stroke
				(width 0.1)
				(type default)
			)
			(layer "F.Fab")
		)
		(fp_line
			(start -0.12065 0.2794)
			(end -0.12065 0.3048)
			(stroke
				(width 0.1)
				(type default)
			)
			(layer "F.Fab")
		)
		(fp_line
			(start 0.120396 0.2794)
			(end -0.12065 0.2794)
			(stroke
				(width 0.1)
				(type default)
			)
			(layer "F.Fab")
		)
		(fp_line
			(start -0.12065 -0.2794)
			(end 0.12065 -0.2794)
			(stroke
				(width 0.1)
				(type default)
			)
			(layer "F.Fab")
		)
		(fp_line
			(start 0.12065 -0.2794)
			(end 0.12065 -0.3048)
			(stroke
				(width 0.1)
				(type default)
			)
			(layer "F.Fab")
		)
		(fp_line
			(start 0.12065 -0.3048)
			(end 0.67945 -0.3048)
			(stroke
				(width 0.1)
				(type default)
			)
			(layer "F.Fab")
		)
		(fp_line
			(start 0.67945 -0.3048)
			(end 0.67945 0.3048)
			(stroke
				(width 0.1)
				(type default)
			)
			(layer "F.Fab")
		)
		(fp_line
			(start -0.67945 -0.305054)
			(end -0.12065 -0.305054)
			(stroke
				(width 0.1)
				(type default)
			)
			(layer "F.Fab")
		)
		(fp_line
			(start -0.12065 -0.305054)
			(end -0.12065 -0.2794)
			(stroke
				(width 0.1)
				(type default)
			)
			(layer "F.Fab")
		)
		(pad "1" smd circle
			(at -0.40005 0 270)
			(size 0 0)
			(layers "F.Cu" "F.Mask" "F.Paste")
			(net "PVDDCR_SOC_P1_EN_RC")
		)
		(pad "2" smd circle
			(at 0.40005 0 270)
			(size 0 0)
			(layers "F.Cu" "F.Mask" "F.Paste")
			(net "GND")
		)
	)
	(footprint ""
		(layer "F.Cu")
		(at 61.874654 -346.721176)
		(property "Reference" "PU36"
			(at -3.200654 -7.455154 0)
			(unlocked yes)
			(layer "F.SilkS")
			(effects
				(font
					(size 0.7874 0.5842)
					(thickness 0.1524)
				)
				(justify left)
			)
		)
		(property "Value" ""
			(at 0 0 0)
			(layer "F.Fab")
			(effects
				(font
					(size 1.27 1.27)
				)
			)
		)
		(duplicate_pad_numbers_are_jumpers no)
		(fp_line
			(start -2.500122 -2.999994)
			(end -2.24409 -2.999994)
			(stroke
				(width 0.1524)
				(type default)
			)
			(layer "F.SilkS")
		)
		(fp_line
			(start -2.500122 -2.529078)
			(end -2.500122 -2.999994)
			(stroke
				(width 0.1524)
				(type default)
			)
			(layer "F.SilkS")
		)
		(fp_line
			(start -2.500122 0.6604)
			(end -2.500122 0.229108)
			(stroke
				(width 0.1524)
				(type default)
			)
			(layer "F.SilkS")
		)
		(fp_line
			(start -2.500122 2.999994)
			(end -2.500122 2.339594)
			(stroke
				(width 0.1524)
				(type default)
			)
			(layer "F.SilkS")
		)
		(fp_line
			(start -2.2987 2.999994)
			(end -2.500122 2.999994)
			(stroke
				(width 0.1524)
				(type default)
			)
			(layer "F.SilkS")
		)
		(fp_line
			(start 2.31394 -2.999994)
			(end 2.500122 -2.999994)
			(stroke
				(width 0.1524)
				(type default)
			)
			(layer "F.SilkS")
		)
		(fp_line
			(start 2.500122 -2.999994)
			(end 2.500122 -2.44348)
			(stroke
				(width 0.1524)
				(type default)
			)
			(layer "F.SilkS")
		)
		(fp_line
			(start 2.500122 2.339594)
			(end 2.500122 2.999994)
			(stroke
				(width 0.1524)
				(type default)
			)
			(layer "F.SilkS")
		)
		(fp_line
			(start 2.500122 2.999994)
			(end 2.2987 2.999994)
			(stroke
				(width 0.1524)
				(type default)
			)
			(layer "F.SilkS")
		)
		(fp_poly
			(pts
				(xy -2.75336 -2.448306) (xy -3.426968 -2.672842) (xy -2.977896 -3.121914)
			)
			(stroke
				(width 0)
				(type default)
			)
			(fill yes)
			(layer "F.SilkS")
		)
		(fp_line
			(start -2.500122 -2.999994)
			(end 2.500122 -2.999994)
			(stroke
				(width 0.1)
				(type default)
			)
			(layer "F.Fab")
		)
		(fp_line
			(start -2.500122 2.999994)
			(end -2.500122 -2.999994)
			(stroke
				(width 0.1)
				(type default)
			)
			(layer "F.Fab")
		)
		(fp_line
			(start 2.500122 -2.999994)
			(end 2.500122 2.999994)
			(stroke
				(width 0.1)
				(type default)
			)
			(layer "F.Fab")
		)
		(fp_line
			(start 2.500122 2.999994)
			(end -2.500122 2.999994)
			(stroke
				(width 0.1)
				(type default)
			)
			(layer "F.Fab")
		)
		(fp_poly
			(pts
				(xy -4.218432 -2.783078) (xy -4.218432 -1.767078) (xy -3.202432 -2.275078)
			)
			(stroke
				(width 0)
				(type default)
			)
			(fill yes)
			(layer "F.Fab")
		)
		(pad "1" smd rect
			(at -2.400046 -2.275078 90)
			(size 0.2286 0.6096)
			(layers "F.Cu" "F.Mask" "F.Paste")
			(net "PVDDCR_CPU1_P1_VOS4")
		)
		(pad "2" smd rect
			(at -2.400046 -1.82499 90)
			(size 0.2286 0.6096)
			(layers "F.Cu" "F.Mask" "F.Paste")
			(net "GND")
		)
		(pad "3" smd rect
			(at -2.400046 -1.374902 90)
			(size 0.2286 0.6096)
			(layers "F.Cu" "F.Mask" "F.Paste")
			(net "PVDDCR_CPU1_P1_VCC4")
		)
		(pad "4" smd rect
			(at -2.400046 -0.925068 90)
			(size 0.2286 0.6096)
			(layers "F.Cu" "F.Mask" "F.Paste")
			(net "PVDDCR_CPU1_P1_PVCC")
		)
		(pad "5" smd rect
			(at -2.400046 -0.47498 90)
			(size 0.2286 0.6096)
			(layers "F.Cu" "F.Mask" "F.Paste")
			(net "GND")
		)
		(pad "6" smd rect
			(at -2.400046 -0.024892 90)
			(size 0.2286 0.6096)
			(layers "F.Cu" "F.Mask" "F.Paste")
			(net "NC_PVDDCR_CPU1_P1_GL1_4")
		)
		(pad "7_9-20_24" smd circle
			(at 0 1.150112 90)
			(size 0 0)
			(layers "F.Cu" "F.Mask" "F.Paste")
			(net "GND")
		)
		(pad "10_19" smd rect
			(at 0 2.899918 90)
			(size 0.6096 4.318)
			(layers "F.Cu" "F.Mask" "F.Paste")
			(net "SW_PVDDCR_CPU1_P1_SW4")
		)
		(pad "25_29" smd rect
			(at 1.549908 -1.279906 270)
			(size 2.0574 2.3114)
			(layers "F.Cu" "F.Mask" "F.Paste")
			(net "SW_P12V_AUX_PVDDCR_CPU1_P1_FLT")
		)
		(pad "30" smd rect
			(at 2.05994 -2.899918)
			(size 0.2286 0.6096)
			(layers "F.Cu" "F.Mask" "F.Paste")
			(net "SW_P12V_AUX_PVDDCR_CPU1_P1_FLT")
		)
		(pad "31" smd rect
			(at 1.610106 -2.899918)
			(size 0.2286 0.6096)
			(layers "F.Cu" "F.Mask" "F.Paste")
			(net "NC_PVDDCR_CPU1_P1_DNC4")
		)
		(pad "32" smd rect
			(at 1.160018 -2.899918)
			(size 0.2286 0.6096)
			(layers "F.Cu" "F.Mask" "F.Paste")
			(net "SW_PVDDCR_CPU1_P1_BOOTR4")
		)
		(pad "33" smd rect
			(at 0.70993 -2.899918)
			(size 0.2286 0.6096)
			(layers "F.Cu" "F.Mask" "F.Paste")
			(net "SW_PVDDCR_CPU1_P1_BOOT4")
		)
		(pad "34" smd rect
			(at 0.260096 -2.899918)
			(size 0.2286 0.6096)
			(layers "F.Cu" "F.Mask" "F.Paste")
			(net "PVDDCR_CPU1_P1_PWM4")
		)
		(pad "35" smd rect
			(at -0.189992 -2.899918)
			(size 0.2286 0.6096)
			(layers "F.Cu" "F.Mask" "F.Paste")
			(net "PVDDCR_CPU1_P1_VCC4")
		)
		(pad "36" smd rect
			(at -0.64008 -2.899918)
			(size 0.2286 0.6096)
			(layers "F.Cu" "F.Mask" "F.Paste")
			(net "PVDDCR_CPU1_P1_TEMP0")
		)
		(pad "37" smd rect
			(at -1.089914 -2.899918)
			(size 0.2286 0.6096)
			(layers "F.Cu" "F.Mask" "F.Paste")
			(net "PVDDCR_CPU1_P1_LSET4")
		)
		(pad "38" smd rect
			(at -1.540002 -2.899918)
			(size 0.2286 0.6096)
			(layers "F.Cu" "F.Mask" "F.Paste")
			(net "PVDDCR_CPU1_P1_IMON4")
		)
		(pad "39" smd rect
			(at -1.99009 -2.899918)
			(size 0.2286 0.6096)
			(layers "F.Cu" "F.Mask" "F.Paste")
			(net "PVDDCR_CPU1_P1_VCCS")
		)
		(pad "40" smd rect
			(at -0.87503 -1.27508)
			(size 1.7526 1.9558)
			(layers "F.Cu" "F.Mask" "F.Paste")
			(net "GND")
		)
		(pad "41" smd rect
			(at -1.525016 0.249936 270)
			(size 0.3048 0.4572)
			(layers "F.Cu" "F.Mask" "F.Paste")
			(net "NC_PVDDCR_CPU1_P1_GL2_4")
		)
		(zone
			(layer "F.Cu")
			(hatch none 0.5)
			(connect_pads
				(clearance 0)
			)
			(min_thickness 0.25)
			(keepout
				(tracks not_allowed)
				(vias allowed)
				(pads allowed)
				(copperpour not_allowed)
				(footprints allowed)
			)
			(placement
				(enabled no)
				(sheetname "")
			)
			(fill
				(thermal_gap 0.5)
				(thermal_bridge_width 0.5)
				(island_removal_mode 0)
			)
			(polygon
				(pts
					(xy 59.374532 -344.141552) (xy 59.374532 -344.470482) (xy 64.374776 -344.470482) (xy 64.374776 -344.136726)
					(xy 64.084454 -344.136726) (xy 64.084454 -344.176858) (xy 59.664854 -344.176858) (xy 59.664854 -344.141552)
				)
			)
		)
		(zone
			(layer "F.Cu")
			(hatch none 0.5)
			(connect_pads
				(clearance 0)
			)
			(min_thickness 0.25)
			(keepout
				(tracks not_allowed)
				(vias allowed)
				(pads allowed)
				(copperpour not_allowed)
				(footprints allowed)
			)
			(placement
				(enabled no)
				(sheetname "")
			)
			(fill
				(thermal_gap 0.5)
				(thermal_bridge_width 0.5)
				(island_removal_mode 0)
			)
			(polygon
				(pts
					(xy 61.926724 -346.967556) (xy 61.926724 -349.024956) (xy 60.072524 -349.024956) (xy 60.072524 -348.78391)
					(xy 59.830208 -348.78391) (xy 59.830208 -349.265494) (xy 63.636652 -349.265494) (xy 63.636652 -349.080582)
					(xy 62.218062 -349.080582) (xy 62.218062 -346.921582) (xy 64.374776 -346.921582) (xy 64.374776 -346.6719)
					(xy 62.22238 -346.6719)
				)
			)
		)
	)
	(footprint ""
		(layer "F.Cu")
		(at 164.740844 -370.57203 -90)
		(property "Reference" "C749"
			(at 0 0 270)
			(layer "F.SilkS")
			(hide yes)
			(effects
				(font
					(size 1.27 1.27)
				)
			)
		)
		(property "Value" ""
			(at 0 0 270)
			(layer "F.Fab")
			(effects
				(font
					(size 1.27 1.27)
				)
			)
		)
		(duplicate_pad_numbers_are_jumpers no)
		(fp_line
			(start -0.299974 0.150114)
			(end -0.299974 -0.150114)
			(stroke
				(width 0.1)
				(type default)
			)
			(layer "F.Fab")
		)
		(fp_line
			(start 0.299974 0.150114)
			(end -0.299974 0.150114)
			(stroke
				(width 0.1)
				(type default)
			)
			(layer "F.Fab")
		)
		(fp_line
			(start -0.299974 -0.150114)
			(end 0.299974 -0.150114)
			(stroke
				(width 0.1)
				(type default)
			)
			(layer "F.Fab")
		)
		(fp_line
			(start 0.299974 -0.150114)
			(end 0.299974 0.150114)
			(stroke
				(width 0.1)
				(type default)
			)
			(layer "F.Fab")
		)
		(pad "1" smd rect
			(at -0.2667 0 270)
			(size 0.3048 0.381)
			(layers "F.Cu" "F.Mask" "F.Paste")
			(net "P5E_CPU1_P2_TX_C_DP<12>")
		)
		(pad "2" smd rect
			(at 0.2667 0 270)
			(size 0.3048 0.381)
			(layers "F.Cu" "F.Mask" "F.Paste")
			(net "P5E_CPU1_P2_TX_DP<12>")
		)
	)
	(footprint ""
		(layer "F.Cu")
		(at 342.799924 -61.999876 180)
		(property "Reference" "J5"
			(at 4.821428 -2.025904 0)
			(unlocked yes)
			(layer "F.SilkS")
			(effects
				(font
					(size 0.7874 0.5842)
					(thickness 0.1524)
				)
			)
		)
		(property "Value" ""
			(at 0 0 180)
			(layer "F.Fab")
			(effects
				(font
					(size 1.27 1.27)
				)
			)
		)
		(duplicate_pad_numbers_are_jumpers no)
		(fp_line
			(start 1.700022 2.739898)
			(end -1.700022 2.739898)
			(stroke
				(width 0.1524)
				(type default)
			)
			(layer "F.SilkS")
		)
		(fp_line
			(start 1.700022 2.4257)
			(end 1.700022 2.739898)
			(stroke
				(width 0.1524)
				(type default)
			)
			(layer "F.SilkS")
		)
		(fp_line
			(start 1.700022 1.1557)
			(end 1.700022 1.3843)
			(stroke
				(width 0.1524)
				(type default)
			)
			(layer "F.SilkS")
		)
		(fp_line
			(start 1.700022 -0.1143)
			(end 1.700022 0.1143)
			(stroke
				(width 0.1524)
				(type default)
			)
			(layer "F.SilkS")
		)
		(fp_line
			(start 1.700022 -1.3843)
			(end 1.700022 -1.1557)
			(stroke
				(width 0.1524)
				(type default)
			)
			(layer "F.SilkS")
		)
		(fp_line
			(start 1.700022 -2.739898)
			(end 1.700022 -2.4257)
			(stroke
				(width 0.1524)
				(type default)
			)
			(layer "F.SilkS")
		)
		(fp_line
			(start -1.700022 2.739898)
			(end -1.700022 2.4257)
			(stroke
				(width 0.1524)
				(type default)
			)
			(layer "F.SilkS")
		)
		(fp_line
			(start -1.700022 1.3843)
			(end -1.700022 1.1557)
			(stroke
				(width 0.1524)
				(type default)
			)
			(layer "F.SilkS")
		)
		(fp_line
			(start -1.700022 0.1143)
			(end -1.700022 -0.1143)
			(stroke
				(width 0.1524)
				(type default)
			)
			(layer "F.SilkS")
		)
		(fp_line
			(start -1.700022 -1.1557)
			(end -1.700022 -1.3843)
			(stroke
				(width 0.1524)
				(type default)
			)
			(layer "F.SilkS")
		)
		(fp_line
			(start -1.700022 -2.4257)
			(end -1.700022 -2.739898)
			(stroke
				(width 0.1524)
				(type default)
			)
			(layer "F.SilkS")
		)
		(fp_line
			(start -1.700022 -2.739898)
			(end 1.700022 -2.739898)
			(stroke
				(width 0.1524)
				(type default)
			)
			(layer "F.SilkS")
		)
		(fp_poly
			(pts
				(xy -3.383534 -1.905) (xy -4.399534 -1.397) (xy -4.399534 -2.413)
			)
			(stroke
				(width 0)
				(type default)
			)
			(fill yes)
			(layer "F.SilkS")
		)
		(fp_line
			(start 1.700022 2.739898)
			(end -1.700022 2.739898)
			(stroke
				(width 0.1)
				(type default)
			)
			(layer "F.Fab")
		)
		(fp_line
			(start 1.700022 -2.739898)
			(end 1.700022 2.739898)
			(stroke
				(width 0.1)
				(type default)
			)
			(layer "F.Fab")
		)
		(fp_line
			(start -1.700022 2.739898)
			(end -1.700022 -2.739898)
			(stroke
				(width 0.1)
				(type default)
			)
			(layer "F.Fab")
		)
		(fp_line
			(start -1.700022 -2.739898)
			(end 1.700022 -2.739898)
			(stroke
				(width 0.1)
				(type default)
			)
			(layer "F.Fab")
		)
		(fp_poly
			(pts
				(xy -4.399534 -2.413) (xy -4.399534 -1.397) (xy -3.383534 -1.905)
			)
			(stroke
				(width 0)
				(type default)
			)
			(fill yes)
			(layer "F.Fab")
		)
		(pad "1" smd rect
			(at -2.050034 -1.905 90)
			(size 0.762 2.413)
			(layers "F.Cu" "F.Mask" "F.Paste")
			(net "CPU0_XTRIG_R1_L4")
		)
		(pad "2" smd rect
			(at 2.050034 -1.905 90)
			(size 0.762 2.413)
			(layers "F.Cu" "F.Mask" "F.Paste")
			(net "GND")
		)
		(pad "3" smd rect
			(at -2.050034 -0.635 90)
			(size 0.762 2.413)
			(layers "F.Cu" "F.Mask" "F.Paste")
			(net "CPU0_XTRIG_R1_L5")
		)
		(pad "4" smd rect
			(at 2.050034 -0.635 90)
			(size 0.762 2.413)
			(layers "F.Cu" "F.Mask" "F.Paste")
			(net "GND")
		)
		(pad "5" smd rect
			(at -2.050034 0.635 90)
			(size 0.762 2.413)
			(layers "F.Cu" "F.Mask" "F.Paste")
			(net "CPU0_XTRIG_R1_L6")
		)
		(pad "6" smd rect
			(at 2.050034 0.635 90)
			(size 0.762 2.413)
			(layers "F.Cu" "F.Mask" "F.Paste")
			(net "GND")
		)
		(pad "7" smd rect
			(at -2.050034 1.905 90)
			(size 0.762 2.413)
			(layers "F.Cu" "F.Mask" "F.Paste")
			(net "CPU0_XTRIG_R1_L7")
		)
		(pad "8" smd rect
			(at 2.050034 1.905 90)
			(size 0.762 2.413)
			(layers "F.Cu" "F.Mask" "F.Paste")
			(net "GND")
		)
	)
)
